(kicad_pcb
	(version 20260206)
	(generator "pcbnew")
	(generator_version "10.0")
	(general
		(thickness 1.6)
		(legacy_teardrops no)
	)
	(paper "A4")
	(title_block
		(title "dpb — 14545-sa.0730WZS0815.brd")
		(comment 1 "Honey Badger (Wiwynn) / footprints 540-547 of 1066")
	)
	(layers
		(0 "F.Cu" signal "TOP")
		(4 "In1.Cu" signal "L2GND")
		(6 "In2.Cu" signal "L3")
		(8 "In3.Cu" signal "L4VCC")
		(10 "In4.Cu" signal "L5VCC")
		(12 "In5.Cu" signal "L6")
		(14 "In6.Cu" signal "L7GND")
		(2 "B.Cu" signal "BOTTOM")
		(9 "F.Adhes" user "F.Adhesive")
		(11 "B.Adhes" user "B.Adhesive")
		(13 "F.Paste" user "Package Geometry/Pastemask Top")
		(15 "B.Paste" user "Package Geometry/Pastemask Bottom")
		(5 "F.SilkS" user "Ref Des/Silkscreen Top")
		(7 "B.SilkS" user "Ref Des/Silkscreen Bottom")
		(1 "F.Mask" user "Board Geometry/Soldermask Top")
		(3 "B.Mask" user "Board Geometry/Soldermask Bottom")
		(17 "Dwgs.User" user "User.Drawings")
		(19 "Cmts.User" user "User.Comments")
		(21 "Eco1.User" user "User.Eco1")
		(23 "Eco2.User" user "User.Eco2")
		(25 "Edge.Cuts" user "Board Geometry/Outline")
		(27 "Margin" user)
		(31 "F.CrtYd" user "Package Geometry/Place Bound Top")
		(29 "B.CrtYd" user "Package Geometry/Place Bound Bottom")
		(35 "F.Fab" user "Ref Des/Assembly Top")
		(33 "B.Fab" user "Ref Des/Assembly Bottom")
	)
	(footprint ""
		(layer "F.Cu")
		(at 240.918746 -27.9527)
		(property "Reference" "PR7"
			(at 0 0 0)
			(layer "F.SilkS")
			(hide yes)
			(effects
				(font
					(size 1.27 1.27)
				)
			)
		)
		(property "Value" "0R2J-2-GP"
			(at 0.064008 -3.993896 0)
			(unlocked yes)
			(layer "F.Fab")
			(hide yes)
			(effects
				(font
					(size 1.016 1.016)
					(thickness 0.1524)
				)
			)
		)
		(property "Device Type" "R402H16"
			(at 0.064008 -5.517896 0)
			(unlocked yes)
			(layer "F.Fab")
			(hide yes)
			(effects
				(font
					(size 1.016 1.016)
					(thickness 0.1524)
				)
			)
		)
		(duplicate_pad_numbers_are_jumpers no)
		(fp_line
			(start -0.508 -0.9398)
			(end -0.508 0.9398)
			(stroke
				(width 0.1524)
				(type default)
			)
			(layer "F.SilkS")
		)
		(fp_line
			(start 0.508 -0.9398)
			(end -0.508 -0.9398)
			(stroke
				(width 0.1524)
				(type default)
			)
			(layer "F.SilkS")
		)
		(fp_rect
			(start -0.508 0.9398)
			(end 0.508 -0.9398)
			(stroke
				(width 0)
				(type default)
			)
			(fill no)
			(layer "F.CrtYd")
		)
		(fp_rect
			(start -0.508 0.9398)
			(end 0.508 -0.9398)
			(stroke
				(width 0)
				(type default)
			)
			(fill no)
			(layer "F.Fab")
		)
		(pad "1" smd custom
			(at 0 -0.4445)
			(size 0.1397 0.1397)
			(layers "F.Cu" "F.Mask" "F.Paste")
			(net "P5VA_MODE_PG")
			(options
				(clearance outline)
				(anchor circle)
			)
			(primitives
				(gr_poly
					(pts
						(arc
							(start -0.1778 -0.2794)
							(mid -0.249642 -0.249642)
							(end -0.2794 -0.1778)
						)
						(arc
							(start -0.2794 0.1778)
							(mid -0.249642 0.249642)
							(end -0.1778 0.2794)
						)
						(arc
							(start 0.1778 0.2794)
							(mid 0.249642 0.249642)
							(end 0.2794 0.1778)
						)
						(arc
							(start 0.2794 -0.1778)
							(mid 0.249642 -0.249642)
							(end 0.1778 -0.2794)
						)
					)
					(width 0)
					(fill yes)
				)
			)
		)
		(pad "2" smd custom
			(at 0 0.4445)
			(size 0.1397 0.1397)
			(layers "F.Cu" "F.Mask" "F.Paste")
			(net "P5VA_MODE")
			(options
				(clearance outline)
				(anchor circle)
			)
			(primitives
				(gr_poly
					(pts
						(arc
							(start -0.1778 -0.2794)
							(mid -0.249642 -0.249642)
							(end -0.2794 -0.1778)
						)
						(arc
							(start -0.2794 0.1778)
							(mid -0.249642 0.249642)
							(end -0.1778 0.2794)
						)
						(arc
							(start 0.1778 0.2794)
							(mid 0.249642 0.249642)
							(end 0.2794 0.1778)
						)
						(arc
							(start 0.2794 -0.1778)
							(mid 0.249642 -0.249642)
							(end 0.1778 -0.2794)
						)
					)
					(width 0)
					(fill yes)
				)
			)
		)
	)
	(footprint ""
		(layer "F.Cu")
		(at 212.5218 -68.8848 180)
		(property "Reference" "Q55"
			(at 0 0 180)
			(layer "F.SilkS")
			(hide yes)
			(effects
				(font
					(size 1.27 1.27)
				)
			)
		)
		(property "Value" "2N7002-11-GP"
			(at 0.127 -8.9662 180)
			(unlocked yes)
			(layer "F.Fab")
			(hide yes)
			(effects
				(font
					(size 1.016 1.016)
					(thickness 0.1524)
				)
			)
		)
		(property "Device Type" "SOT23DGS2D4H44"
			(at 0.127 -10.4902 180)
			(unlocked yes)
			(layer "F.Fab")
			(hide yes)
			(effects
				(font
					(size 1.016 1.016)
					(thickness 0.1524)
				)
			)
		)
		(duplicate_pad_numbers_are_jumpers no)
		(fp_line
			(start 1.651 1.778)
			(end 1.651 -1.778)
			(stroke
				(width 0.1524)
				(type default)
			)
			(layer "F.SilkS")
		)
		(fp_line
			(start 1.651 -1.778)
			(end -1.651 -1.778)
			(stroke
				(width 0.1524)
				(type default)
			)
			(layer "F.SilkS")
		)
		(fp_line
			(start -1.651 1.778)
			(end 1.651 1.778)
			(stroke
				(width 0.1524)
				(type default)
			)
			(layer "F.SilkS")
		)
		(fp_line
			(start -1.651 -1.778)
			(end -1.651 1.778)
			(stroke
				(width 0.1524)
				(type default)
			)
			(layer "F.SilkS")
		)
		(fp_poly
			(pts
				(xy -1.778 1.8796) (xy -1.778 -1.8796) (xy 1.778 -1.8796) (xy 1.778 1.8796)
			)
			(stroke
				(width 0)
				(type default)
			)
			(fill no)
			(layer "F.CrtYd")
		)
		(fp_poly
			(pts
				(xy -1.778 1.8796) (xy -1.778 -1.8796) (xy 1.778 -1.8796) (xy 1.778 1.8796)
			)
			(stroke
				(width 0)
				(type default)
			)
			(fill no)
			(layer "F.Fab")
		)
		(pad "D" smd custom
			(at 0 -0.9525 180)
			(size 0.1905 0.1905)
			(layers "F.Cu" "F.Mask" "F.Paste")
			(net "HDD4_LED_G")
			(options
				(clearance outline)
				(anchor circle)
			)
			(primitives
				(gr_poly
					(pts
						(arc
							(start -0.1778 0.5715)
							(mid -0.321484 0.511984)
							(end -0.381 0.3683)
						)
						(arc
							(start -0.381 -0.3683)
							(mid -0.321484 -0.511984)
							(end -0.1778 -0.5715)
						)
						(arc
							(start 0.1778 -0.5715)
							(mid 0.321484 -0.511984)
							(end 0.381 -0.3683)
						)
						(arc
							(start 0.381 0.3683)
							(mid 0.321484 0.511984)
							(end 0.1778 0.5715)
						)
					)
					(width 0)
					(fill yes)
				)
			)
		)
		(pad "G" smd custom
			(at -0.98425 0.9525 180)
			(size 0.1905 0.1905)
			(layers "F.Cu" "F.Mask" "F.Paste")
			(net "HDD4_LED_B")
			(options
				(clearance outline)
				(anchor circle)
			)
			(primitives
				(gr_poly
					(pts
						(arc
							(start -0.1778 0.5715)
							(mid -0.321484 0.511984)
							(end -0.381 0.3683)
						)
						(arc
							(start -0.381 -0.3683)
							(mid -0.321484 -0.511984)
							(end -0.1778 -0.5715)
						)
						(arc
							(start 0.1778 -0.5715)
							(mid 0.321484 -0.511984)
							(end 0.381 -0.3683)
						)
						(arc
							(start 0.381 0.3683)
							(mid 0.321484 0.511984)
							(end 0.1778 0.5715)
						)
					)
					(width 0)
					(fill yes)
				)
			)
		)
		(pad "S" smd custom
			(at 0.98425 0.9525 180)
			(size 0.1905 0.1905)
			(layers "F.Cu" "F.Mask" "F.Paste")
			(net "GND")
			(options
				(clearance outline)
				(anchor circle)
			)
			(primitives
				(gr_poly
					(pts
						(arc
							(start -0.1778 0.5715)
							(mid -0.321484 0.511984)
							(end -0.381 0.3683)
						)
						(arc
							(start -0.381 -0.3683)
							(mid -0.321484 -0.511984)
							(end -0.1778 -0.5715)
						)
						(arc
							(start 0.1778 -0.5715)
							(mid 0.321484 -0.511984)
							(end 0.381 -0.3683)
						)
						(arc
							(start 0.381 0.3683)
							(mid 0.321484 0.511984)
							(end 0.1778 0.5715)
						)
					)
					(width 0)
					(fill yes)
				)
			)
		)
	)
	(footprint ""
		(layer "F.Cu")
		(at 52.832 -206.375 90)
		(property "Reference" "D27"
			(at 0 0 90)
			(layer "F.SilkS")
			(hide yes)
			(effects
				(font
					(size 1.27 1.27)
				)
			)
		)
		(property "Value" "RB551V30-1-GP"
			(at 0 -6.7818 90)
			(unlocked yes)
			(layer "F.Fab")
			(hide yes)
			(effects
				(font
					(size 1.016 1.016)
					(thickness 0.1524)
				)
			)
		)
		(property "Device Type" "SOD323AKH44"
			(at 0 -8.6868 90)
			(unlocked yes)
			(layer "F.Fab")
			(hide yes)
			(effects
				(font
					(size 1.016 1.016)
					(thickness 0.1524)
				)
			)
		)
		(duplicate_pad_numbers_are_jumpers no)
		(fp_line
			(start 0.889 -1.9304)
			(end 0.889 2.159)
			(stroke
				(width 0.1524)
				(type default)
			)
			(layer "F.SilkS")
		)
		(fp_line
			(start -0.889 -1.9304)
			(end 0.889 -1.9304)
			(stroke
				(width 0.1524)
				(type default)
			)
			(layer "F.SilkS")
		)
		(fp_line
			(start 0.762 2.0574)
			(end -0.762 2.0574)
			(stroke
				(width 0.508)
				(type default)
			)
			(layer "F.SilkS")
		)
		(fp_line
			(start 0.889 2.159)
			(end -0.889 2.159)
			(stroke
				(width 0.1524)
				(type default)
			)
			(layer "F.SilkS")
		)
		(fp_line
			(start -0.889 2.159)
			(end -0.889 -1.9304)
			(stroke
				(width 0.1524)
				(type default)
			)
			(layer "F.SilkS")
		)
		(fp_rect
			(start -1.016 2.3114)
			(end 1.016 -2.0066)
			(stroke
				(width 0)
				(type default)
			)
			(fill no)
			(layer "F.CrtYd")
		)
		(fp_poly
			(pts
				(xy -1.016 -2.0066) (xy 1.016 -2.0066) (xy 1.016 2.3114) (xy -1.016 2.3114)
			)
			(stroke
				(width 0)
				(type default)
			)
			(fill no)
			(layer "F.Fab")
		)
		(pad "A" smd rect
			(at 0 -1.143 90)
			(size 0.5588 1.016)
			(layers "F.Cu" "F.Mask" "F.Paste")
			(net "SW_HDD12_R")
		)
		(pad "K" smd rect
			(at 0 1.143 90)
			(size 0.5588 1.016)
			(layers "F.Cu" "F.Mask" "F.Paste")
			(net "SW_HDD12_N")
		)
	)
	(footprint ""
		(layer "F.Cu")
		(at 35.941 -306.324 -90)
		(property "Reference" "C390"
			(at 0 0 270)
			(layer "F.SilkS")
			(hide yes)
			(effects
				(font
					(size 1.27 1.27)
				)
			)
		)
		(property "Value" "SCD033U25V2KX-GP"
			(at 1.1811 -2.7051 270)
			(unlocked yes)
			(layer "F.Fab")
			(hide yes)
			(effects
				(font
					(size 1.016 1.016)
					(thickness 0.1524)
				)
			)
		)
		(property "Device Type" "C402H22"
			(at 1.1811 -4.2291 270)
			(unlocked yes)
			(layer "F.Fab")
			(hide yes)
			(effects
				(font
					(size 1.016 1.016)
					(thickness 0.1524)
				)
			)
		)
		(duplicate_pad_numbers_are_jumpers no)
		(fp_rect
			(start -0.4318 0.9525)
			(end 0.4318 -0.9525)
			(stroke
				(width 0)
				(type default)
			)
			(fill no)
			(layer "F.CrtYd")
		)
		(fp_rect
			(start -0.4318 0.9525)
			(end 0.4318 -0.9525)
			(stroke
				(width 0)
				(type default)
			)
			(fill no)
			(layer "F.Fab")
		)
		(pad "1" smd custom
			(at 0 -0.4445 270)
			(size 0.1524 0.1524)
			(layers "F.Cu" "F.Mask" "F.Paste")
			(net "P12V")
			(options
				(clearance outline)
				(anchor circle)
			)
			(primitives
				(gr_poly
					(pts
						(arc
							(start 0.3048 -0.2032)
							(mid 0.275042 -0.275042)
							(end 0.2032 -0.3048)
						)
						(arc
							(start -0.2032 -0.3048)
							(mid -0.275042 -0.275042)
							(end -0.3048 -0.2032)
						)
						(arc
							(start -0.3048 0.2032)
							(mid -0.275042 0.275042)
							(end -0.2032 0.3048)
						)
						(arc
							(start 0.2032 0.3048)
							(mid 0.275042 0.275042)
							(end 0.3048 0.2032)
						)
					)
					(width 0)
					(fill yes)
				)
			)
		)
		(pad "2" smd custom
			(at 0 0.4445 270)
			(size 0.1524 0.1524)
			(layers "F.Cu" "F.Mask" "F.Paste")
			(net "SW_HDD11_N")
			(options
				(clearance outline)
				(anchor circle)
			)
			(primitives
				(gr_poly
					(pts
						(arc
							(start 0.3048 -0.2032)
							(mid 0.275042 -0.275042)
							(end 0.2032 -0.3048)
						)
						(arc
							(start -0.2032 -0.3048)
							(mid -0.275042 -0.275042)
							(end -0.3048 -0.2032)
						)
						(arc
							(start -0.3048 0.2032)
							(mid -0.275042 0.275042)
							(end -0.2032 0.3048)
						)
						(arc
							(start 0.2032 0.3048)
							(mid 0.275042 0.275042)
							(end 0.3048 0.2032)
						)
					)
					(width 0)
					(fill yes)
				)
			)
		)
	)
	(footprint ""
		(layer "F.Cu")
		(at 31.242 -288.29 180)
		(property "Reference" "C386"
			(at 0 0 180)
			(layer "F.SilkS")
			(hide yes)
			(effects
				(font
					(size 1.27 1.27)
				)
			)
		)
		(property "Value" "SCD033U25V2KX-GP"
			(at 1.1811 -2.7051 180)
			(unlocked yes)
			(layer "F.Fab")
			(hide yes)
			(effects
				(font
					(size 1.016 1.016)
					(thickness 0.1524)
				)
			)
		)
		(property "Device Type" "C402H22"
			(at 1.1811 -4.2291 180)
			(unlocked yes)
			(layer "F.Fab")
			(hide yes)
			(effects
				(font
					(size 1.016 1.016)
					(thickness 0.1524)
				)
			)
		)
		(duplicate_pad_numbers_are_jumpers no)
		(fp_rect
			(start -0.4318 0.9525)
			(end 0.4318 -0.9525)
			(stroke
				(width 0)
				(type default)
			)
			(fill no)
			(layer "F.CrtYd")
		)
		(fp_rect
			(start -0.4318 0.9525)
			(end 0.4318 -0.9525)
			(stroke
				(width 0)
				(type default)
			)
			(fill no)
			(layer "F.Fab")
		)
		(pad "1" smd custom
			(at 0 -0.4445 180)
			(size 0.1524 0.1524)
			(layers "F.Cu" "F.Mask" "F.Paste")
			(net "P12V")
			(options
				(clearance outline)
				(anchor circle)
			)
			(primitives
				(gr_poly
					(pts
						(arc
							(start 0.3048 -0.2032)
							(mid 0.275042 -0.275042)
							(end 0.2032 -0.3048)
						)
						(arc
							(start -0.2032 -0.3048)
							(mid -0.275042 -0.275042)
							(end -0.3048 -0.2032)
						)
						(arc
							(start -0.3048 0.2032)
							(mid -0.275042 0.275042)
							(end -0.2032 0.3048)
						)
						(arc
							(start 0.2032 0.3048)
							(mid 0.275042 0.275042)
							(end 0.3048 0.2032)
						)
					)
					(width 0)
					(fill yes)
				)
			)
		)
		(pad "2" smd custom
			(at 0 0.4445 180)
			(size 0.1524 0.1524)
			(layers "F.Cu" "F.Mask" "F.Paste")
			(net "SW_HDD7_N")
			(options
				(clearance outline)
				(anchor circle)
			)
			(primitives
				(gr_poly
					(pts
						(arc
							(start 0.3048 -0.2032)
							(mid 0.275042 -0.275042)
							(end 0.2032 -0.3048)
						)
						(arc
							(start -0.2032 -0.3048)
							(mid -0.275042 -0.275042)
							(end -0.3048 -0.2032)
						)
						(arc
							(start -0.3048 0.2032)
							(mid -0.275042 0.275042)
							(end -0.2032 0.3048)
						)
						(arc
							(start 0.2032 0.3048)
							(mid 0.275042 0.275042)
							(end 0.3048 0.2032)
						)
					)
					(width 0)
					(fill yes)
				)
			)
		)
	)
	(footprint ""
		(layer "F.Cu")
		(at 92.583 -13.462 -90)
		(property "Reference" "D29"
			(at 0 0 270)
			(layer "F.SilkS")
			(hide yes)
			(effects
				(font
					(size 1.27 1.27)
				)
			)
		)
		(property "Value" "RB551V30-1-GP"
			(at 0 -6.7818 270)
			(unlocked yes)
			(layer "F.Fab")
			(hide yes)
			(effects
				(font
					(size 1.016 1.016)
					(thickness 0.1524)
				)
			)
		)
		(property "Device Type" "SOD323AKH44"
			(at 0 -8.6868 270)
			(unlocked yes)
			(layer "F.Fab")
			(hide yes)
			(effects
				(font
					(size 1.016 1.016)
					(thickness 0.1524)
				)
			)
		)
		(duplicate_pad_numbers_are_jumpers no)
		(fp_line
			(start -0.889 2.159)
			(end -0.889 -1.9304)
			(stroke
				(width 0.1524)
				(type default)
			)
			(layer "F.SilkS")
		)
		(fp_line
			(start 0.889 2.159)
			(end -0.889 2.159)
			(stroke
				(width 0.1524)
				(type default)
			)
			(layer "F.SilkS")
		)
		(fp_line
			(start 0.762 2.0574)
			(end -0.762 2.0574)
			(stroke
				(width 0.508)
				(type default)
			)
			(layer "F.SilkS")
		)
		(fp_line
			(start -0.889 -1.9304)
			(end 0.889 -1.9304)
			(stroke
				(width 0.1524)
				(type default)
			)
			(layer "F.SilkS")
		)
		(fp_line
			(start 0.889 -1.9304)
			(end 0.889 2.159)
			(stroke
				(width 0.1524)
				(type default)
			)
			(layer "F.SilkS")
		)
		(fp_rect
			(start -1.016 2.3114)
			(end 1.016 -2.0066)
			(stroke
				(width 0)
				(type default)
			)
			(fill no)
			(layer "F.CrtYd")
		)
		(fp_poly
			(pts
				(xy -1.016 -2.0066) (xy 1.016 -2.0066) (xy 1.016 2.3114) (xy -1.016 2.3114)
			)
			(stroke
				(width 0)
				(type default)
			)
			(fill no)
			(layer "F.Fab")
		)
		(pad "A" smd rect
			(at 0 -1.143 270)
			(size 0.5588 1.016)
			(layers "F.Cu" "F.Mask" "F.Paste")
			(net "SW_HDD14_R")
		)
		(pad "K" smd rect
			(at 0 1.143 270)
			(size 0.5588 1.016)
			(layers "F.Cu" "F.Mask" "F.Paste")
			(net "SW_HDD14_N")
		)
	)
	(footprint ""
		(layer "F.Cu")
		(at 210.185 -68.3768)
		(property "Reference" "R370"
			(at 0 0 0)
			(layer "F.SilkS")
			(hide yes)
			(effects
				(font
					(size 1.27 1.27)
				)
			)
		)
		(property "Value" "10KR2F-2-GP"
			(at 0.064008 -3.993896 0)
			(unlocked yes)
			(layer "F.Fab")
			(hide yes)
			(effects
				(font
					(size 1.016 1.016)
					(thickness 0.1524)
				)
			)
		)
		(property "Device Type" "R402H16"
			(at 0.064008 -5.517896 0)
			(unlocked yes)
			(layer "F.Fab")
			(hide yes)
			(effects
				(font
					(size 1.016 1.016)
					(thickness 0.1524)
				)
			)
		)
		(duplicate_pad_numbers_are_jumpers no)
		(fp_line
			(start -0.508 -0.9398)
			(end -0.508 0.9398)
			(stroke
				(width 0.1524)
				(type default)
			)
			(layer "F.SilkS")
		)
		(fp_line
			(start 0.508 -0.9398)
			(end -0.508 -0.9398)
			(stroke
				(width 0.1524)
				(type default)
			)
			(layer "F.SilkS")
		)
		(fp_rect
			(start -0.508 0.9398)
			(end 0.508 -0.9398)
			(stroke
				(width 0)
				(type default)
			)
			(fill no)
			(layer "F.CrtYd")
		)
		(fp_rect
			(start -0.508 0.9398)
			(end 0.508 -0.9398)
			(stroke
				(width 0)
				(type default)
			)
			(fill no)
			(layer "F.Fab")
		)
		(pad "1" smd custom
			(at 0 -0.4445)
			(size 0.1397 0.1397)
			(layers "F.Cu" "F.Mask" "F.Paste")
			(net "P12V")
			(options
				(clearance outline)
				(anchor circle)
			)
			(primitives
				(gr_poly
					(pts
						(arc
							(start -0.1778 -0.2794)
							(mid -0.249642 -0.249642)
							(end -0.2794 -0.1778)
						)
						(arc
							(start -0.2794 0.1778)
							(mid -0.249642 0.249642)
							(end -0.1778 0.2794)
						)
						(arc
							(start 0.1778 0.2794)
							(mid 0.249642 0.249642)
							(end 0.2794 0.1778)
						)
						(arc
							(start 0.2794 -0.1778)
							(mid 0.249642 -0.249642)
							(end 0.1778 -0.2794)
						)
					)
					(width 0)
					(fill yes)
				)
			)
		)
		(pad "2" smd custom
			(at 0 0.4445)
			(size 0.1397 0.1397)
			(layers "F.Cu" "F.Mask" "F.Paste")
			(net "HDD4_LED_G")
			(options
				(clearance outline)
				(anchor circle)
			)
			(primitives
				(gr_poly
					(pts
						(arc
							(start -0.1778 -0.2794)
							(mid -0.249642 -0.249642)
							(end -0.2794 -0.1778)
						)
						(arc
							(start -0.2794 0.1778)
							(mid -0.249642 0.249642)
							(end -0.1778 0.2794)
						)
						(arc
							(start 0.1778 0.2794)
							(mid 0.249642 0.249642)
							(end 0.2794 0.1778)
						)
						(arc
							(start 0.2794 -0.1778)
							(mid 0.249642 -0.249642)
							(end 0.1778 -0.2794)
						)
					)
					(width 0)
					(fill yes)
				)
			)
		)
	)
	(footprint ""
		(layer "F.Cu")
		(at 14.5796 -155.1686)
		(property "Reference" "TP12"
			(at 0 0 0)
			(layer "F.SilkS")
			(hide yes)
			(effects
				(font
					(size 1.27 1.27)
				)
			)
		)
		(property "Value" "TPAD32-GP"
			(at 0 -3.166364 0)
			(unlocked yes)
			(layer "F.Fab")
			(hide yes)
			(effects
				(font
					(size 1.016 1.016)
					(thickness 0.1524)
				)
			)
		)
		(property "Device Type" "TPAD32"
			(at 0 -4.690618 0)
			(unlocked yes)
			(layer "F.Fab")
			(hide yes)
			(effects
				(font
					(size 1.016 1.016)
					(thickness 0.1524)
				)
			)
		)
		(duplicate_pad_numbers_are_jumpers no)
		(fp_poly
			(pts
				(arc
					(start 0.4064 0)
					(mid -0.4064 0)
					(end 0.4064 0)
				)
			)
			(stroke
				(width 0)
				(type default)
			)
			(fill no)
			(layer "F.CrtYd")
		)
		(fp_poly
			(pts
				(arc
					(start 0.7112 0)
					(mid -0.7112 0)
					(end 0.7112 0)
				)
			)
			(stroke
				(width 0)
				(type default)
			)
			(fill no)
			(layer "F.Fab")
		)
		(pad "1" smd circle
			(at 0 0)
			(size 0.8128 0.8128)
			(layers "F.Cu" "F.Mask" "F.Paste")
			(net "SAS2X28_B_HDD15_FLT")
		)
	)
)
